(kicad_pcb
	(version 20260206)
	(generator "pcbnew")
	(generator_version "10.0")
	(general
		(thickness 1.6)
		(legacy_teardrops no)
	)
	(paper "A4")
	(title_block
		(title "Bryce Canyon_R.DPB_16317-1_OCP.brd")
		(comment 1 "Bryce Canyon / footprints 358-360 of 2099")
	)
	(layers
		(0 "F.Cu" signal "TOP")
		(4 "In1.Cu" signal "L2GND")
		(6 "In2.Cu" signal "L3")
		(8 "In3.Cu" signal "L4VCC")
		(10 "In4.Cu" signal "L5VCC")
		(12 "In5.Cu" signal "L6")
		(14 "In6.Cu" signal "L7GND")
		(2 "B.Cu" signal "BOTTOM")
		(9 "F.Adhes" user "F.Adhesive")
		(11 "B.Adhes" user "B.Adhesive")
		(13 "F.Paste" user "Package Geometry/Pastemask Top")
		(15 "B.Paste" user "Package Geometry/Pastemask Bottom")
		(5 "F.SilkS" user "Ref Des/Silkscreen Top")
		(7 "B.SilkS" user "Ref Des/Silkscreen Bottom")
		(1 "F.Mask" user "Board Geometry/Soldermask Top")
		(3 "B.Mask" user "Board Geometry/Soldermask Bottom")
		(17 "Dwgs.User" user "User.Drawings")
		(19 "Cmts.User" user "User.Comments")
		(21 "Eco1.User" user "User.Eco1")
		(23 "Eco2.User" user "User.Eco2")
		(25 "Edge.Cuts" user "Board Geometry/Outline")
		(27 "Margin" user)
		(31 "F.CrtYd" user "Package Geometry/Place Bound Top")
		(29 "B.CrtYd" user "Package Geometry/Place Bound Bottom")
		(35 "F.Fab" user "Ref Des/Assembly Top")
		(33 "B.Fab" user "Ref Des/Assembly Bottom")
	)
	(footprint ""
		(layer "F.Cu")
		(at 451.749922 -258.910074 -90)
		(property "Reference" "HDDSAS10"
			(at 0 0 270)
			(layer "F.SilkS")
			(hide yes)
			(effects
				(font
					(size 1.27 1.27)
				)
			)
		)
		(property "Value" "SKT-SAS15P-14P-45-GP"
			(at -20.7645 -8.9789 270)
			(unlocked yes)
			(layer "F.Fab")
			(hide yes)
			(effects
				(font
					(size 1.016 1.016)
					(thickness 0.1524)
				)
			)
		)
		(property "Device Type" "10120818-001C-TRLF"
			(at -20.7645 -10.5029 270)
			(unlocked yes)
			(layer "F.Fab")
			(hide yes)
			(effects
				(font
					(size 1.016 1.016)
					(thickness 0.1524)
				)
			)
		)
		(duplicate_pad_numbers_are_jumpers no)
		(fp_line
			(start 1.651 4.2926)
			(end 1.651 3.0099)
			(stroke
				(width 0.1524)
				(type default)
			)
			(layer "F.SilkS")
		)
		(fp_line
			(start 8.509 4.2926)
			(end 1.651 4.2926)
			(stroke
				(width 0.1524)
				(type default)
			)
			(layer "F.SilkS")
		)
		(fp_line
			(start -23.4188 3.0099)
			(end -23.4188 -3.2512)
			(stroke
				(width 0.1524)
				(type default)
			)
			(layer "F.SilkS")
		)
		(fp_line
			(start 1.651 3.0099)
			(end -23.4188 3.0099)
			(stroke
				(width 0.1524)
				(type default)
			)
			(layer "F.SilkS")
		)
		(fp_line
			(start 8.509 3.0099)
			(end 8.509 4.2926)
			(stroke
				(width 0.1524)
				(type default)
			)
			(layer "F.SilkS")
		)
		(fp_line
			(start 23.4188 3.0099)
			(end 8.509 3.0099)
			(stroke
				(width 0.1524)
				(type default)
			)
			(layer "F.SilkS")
		)
		(fp_line
			(start -23.4188 -3.2512)
			(end 23.4188 -3.2512)
			(stroke
				(width 0.1524)
				(type default)
			)
			(layer "F.SilkS")
		)
		(fp_line
			(start 23.4188 -3.2512)
			(end 23.4188 3.0099)
			(stroke
				(width 0.1524)
				(type default)
			)
			(layer "F.SilkS")
		)
		(fp_line
			(start 15.5067 -3.3401)
			(end 16.2687 -3.3401)
			(stroke
				(width 0.3302)
				(type default)
			)
			(layer "F.SilkS")
		)
		(fp_poly
			(pts
				(xy 15.868904 -3.230372) (xy 16.503904 -3.865372) (xy 15.233904 -3.865372)
			)
			(stroke
				(width 0)
				(type default)
			)
			(fill yes)
			(layer "F.SilkS")
		)
		(fp_poly
			(pts
				(xy -22.8727 -2.7559) (xy 22.8727 -2.7559) (xy 22.8727 2.7559) (xy 8.255 2.7559) (xy 8.255 3.5179)
				(xy 1.905 3.5179) (xy 1.905 2.7559) (xy -22.8727 2.7559)
			)
			(stroke
				(width 0)
				(type default)
			)
			(fill no)
			(layer "F.CrtYd")
		)
		(fp_poly
			(pts
				(xy 1.397 4.5466) (xy 1.397 3.2639) (xy -23.6728 3.2639) (xy -23.6728 -3.5052) (xy 23.6728 -3.5052)
				(xy 23.6728 -0.00635) (xy 22.8727 -0.00635) (xy 22.8727 -2.7559) (xy -22.8727 -2.7559) (xy -22.8727 2.7559)
				(xy 1.905 2.7559) (xy 1.905 3.5179) (xy 8.255 3.5179) (xy 8.255 2.7559) (xy 22.8727 2.7559) (xy 22.8727 0.00635)
				(xy 23.6728 0.00635) (xy 23.6728 3.2639) (xy 8.763 3.2639) (xy 8.763 4.5466)
			)
			(stroke
				(width 0)
				(type default)
			)
			(fill no)
			(layer "F.CrtYd")
		)
		(fp_poly
			(pts
				(xy 1.397 4.5466) (xy 1.397 3.2639) (xy -23.6728 3.2639) (xy -23.6728 -3.5052) (xy 23.6728 -3.5052)
				(xy 23.6728 3.2639) (xy 8.763 3.2639) (xy 8.763 4.5466)
			)
			(stroke
				(width 0)
				(type default)
			)
			(fill no)
			(layer "F.Fab")
		)
		(pad "" np_thru_hole circle
			(at -18.874994 0 270)
			(size 0.254 0.254)
			(drill 1.3462)
			(layers "*.Cu" "*.Mask")
			(clearance 0.9017)
			(thermal_gap 0.9017)
		)
		(pad "" np_thru_hole circle
			(at 18.874994 0 270)
			(size 0.254 0.254)
			(drill 0.9398)
			(layers "*.Cu" "*.Mask")
			(clearance 0.6985)
			(thermal_gap 0.6985)
		)
		(pad "G1" smd rect
			(at 21.874988 0 270)
			(size 2.5908 2.5908)
			(layers "F.Cu" "F.Mask" "F.Paste")
			(net "GND")
		)
		(pad "G2" smd rect
			(at -21.874988 0 270)
			(size 2.5908 2.5908)
			(layers "F.Cu" "F.Mask" "F.Paste")
			(net "GND")
		)
		(pad "P1" smd rect
			(at 1.905 -1.82499 270)
			(size 0.6096 2.3622)
			(layers "F.Cu" "F.Mask" "F.Paste")
			(net "Net_1754")
		)
		(pad "P2" smd rect
			(at 0.635 -1.82499 270)
			(size 0.6096 2.3622)
			(layers "F.Cu" "F.Mask" "F.Paste")
			(net "Net_1755")
		)
		(pad "P3" smd rect
			(at -0.635 -1.82499 270)
			(size 0.6096 2.3622)
			(layers "F.Cu" "F.Mask" "F.Paste")
			(net "Net_1756")
		)
		(pad "P4" smd rect
			(at -1.905 -1.82499 270)
			(size 0.6096 2.3622)
			(layers "F.Cu" "F.Mask" "F.Paste")
			(net "GND")
		)
		(pad "P5" smd rect
			(at -3.175 -1.82499 270)
			(size 0.6096 2.3622)
			(layers "F.Cu" "F.Mask" "F.Paste")
			(net "HDD_PRSNT_10")
		)
		(pad "P6" smd rect
			(at -4.445 -1.82499 270)
			(size 0.6096 2.3622)
			(layers "F.Cu" "F.Mask" "F.Paste")
			(net "GND")
		)
		(pad "P7" smd rect
			(at -5.715 -1.82499 270)
			(size 0.6096 2.3622)
			(layers "F.Cu" "F.Mask" "F.Paste")
			(net "5V_PRE_10")
		)
		(pad "P8" smd rect
			(at -6.985 -1.82499 270)
			(size 0.6096 2.3622)
			(layers "F.Cu" "F.Mask" "F.Paste")
			(net "P5V_HDD10")
		)
		(pad "P9" smd rect
			(at -8.255 -1.82499 270)
			(size 0.6096 2.3622)
			(layers "F.Cu" "F.Mask" "F.Paste")
			(net "P5V_HDD10")
		)
		(pad "P10" smd rect
			(at -9.525 -1.82499 270)
			(size 0.6096 2.3622)
			(layers "F.Cu" "F.Mask" "F.Paste")
			(net "GND")
		)
		(pad "P11" smd rect
			(at -10.795 -1.82499 270)
			(size 0.6096 2.3622)
			(layers "F.Cu" "F.Mask" "F.Paste")
			(net "ACT_HDD_10")
		)
		(pad "P12" smd rect
			(at -12.065 -1.82499 270)
			(size 0.6096 2.3622)
			(layers "F.Cu" "F.Mask" "F.Paste")
			(net "GND")
		)
		(pad "P13" smd rect
			(at -13.335 -1.82499 270)
			(size 0.6096 2.3622)
			(layers "F.Cu" "F.Mask" "F.Paste")
			(net "12V_PRE_10")
		)
		(pad "P14" smd rect
			(at -14.605 -1.82499 270)
			(size 0.6096 2.3622)
			(layers "F.Cu" "F.Mask" "F.Paste")
			(net "P12V_HDD10")
		)
		(pad "P15" smd rect
			(at -15.875 -1.82499 270)
			(size 0.6096 2.3622)
			(layers "F.Cu" "F.Mask" "F.Paste")
			(net "P12V_HDD10")
		)
		(pad "S1" smd rect
			(at 15.875 -1.82499 270)
			(size 0.6096 2.3622)
			(layers "F.Cu" "F.Mask" "F.Paste")
			(net "GND")
		)
		(pad "S2" smd rect
			(at 14.605 -1.82499 270)
			(size 0.6096 2.3622)
			(layers "F.Cu" "F.Mask" "F.Paste")
			(net "SAS_HDD_RX_P10")
		)
		(pad "S3" smd rect
			(at 13.335 -1.82499 270)
			(size 0.6096 2.3622)
			(layers "F.Cu" "F.Mask" "F.Paste")
			(net "SAS_HDD_RX_N10")
		)
		(pad "S4" smd rect
			(at 12.065 -1.82499 270)
			(size 0.6096 2.3622)
			(layers "F.Cu" "F.Mask" "F.Paste")
			(net "GND")
		)
		(pad "S5" smd rect
			(at 10.795 -1.82499 270)
			(size 0.6096 2.3622)
			(layers "F.Cu" "F.Mask" "F.Paste")
			(net "PHY_DRV_B_TO_SCC_B_10_DN")
		)
		(pad "S6" smd rect
			(at 9.525 -1.82499 270)
			(size 0.6096 2.3622)
			(layers "F.Cu" "F.Mask" "F.Paste")
			(net "PHY_DRV_B_TO_SCC_B_10_DP")
		)
		(pad "S7" smd rect
			(at 8.255 -1.82499 270)
			(size 0.6096 2.3622)
			(layers "F.Cu" "F.Mask" "F.Paste")
			(net "GND")
		)
		(pad "S8" smd rect
			(at 7.480046 2.845054 270)
			(size 0.508 2.3622)
			(layers "F.Cu" "F.Mask" "F.Paste")
			(net "GND")
		)
		(pad "S9" smd rect
			(at 6.679946 2.845054 270)
			(size 0.508 2.3622)
			(layers "F.Cu" "F.Mask" "F.Paste")
			(net "Net_433")
		)
		(pad "S10" smd rect
			(at 5.8801 2.845054 270)
			(size 0.508 2.3622)
			(layers "F.Cu" "F.Mask" "F.Paste")
			(net "Net_325")
		)
		(pad "S11" smd rect
			(at 5.08 2.845054 270)
			(size 0.508 2.3622)
			(layers "F.Cu" "F.Mask" "F.Paste")
			(net "GND")
		)
		(pad "S12" smd rect
			(at 4.2799 2.845054 270)
			(size 0.508 2.3622)
			(layers "F.Cu" "F.Mask" "F.Paste")
			(net "Net_361")
		)
		(pad "S13" smd rect
			(at 3.480054 2.845054 270)
			(size 0.508 2.3622)
			(layers "F.Cu" "F.Mask" "F.Paste")
			(net "Net_397")
		)
		(pad "S14" smd rect
			(at 2.679954 2.845054 270)
			(size 0.508 2.3622)
			(layers "F.Cu" "F.Mask" "F.Paste")
			(net "GND")
		)
		(zone
			(layer "F.Cu")
			(hatch none 0.5)
			(connect_pads
				(clearance 0)
			)
			(min_thickness 0.25)
			(keepout
				(tracks not_allowed)
				(vias allowed)
				(pads allowed)
				(copperpour not_allowed)
				(footprints allowed)
			)
			(placement
				(enabled no)
				(sheetname "")
			)
			(fill
				(thermal_gap 0.5)
				(thermal_bridge_width 0.5)
				(island_removal_mode 0)
			)
			(polygon
				(pts
					(xy 455.407522 -275.648674) (xy 448.333622 -275.648674) (xy 448.333622 -282.582874) (xy 449.438522 -282.582874)
					(xy 449.438522 -278.468074) (xy 454.061322 -278.468074) (xy 454.061322 -282.582874) (xy 455.407522 -282.582874)
				)
			)
		)
		(zone
			(layer "F.Cu")
			(hatch none 0.5)
			(connect_pads
				(clearance 0)
			)
			(min_thickness 0.25)
			(keepout
				(tracks allowed)
				(vias not_allowed)
				(pads allowed)
				(copperpour not_allowed)
				(footprints allowed)
			)
			(placement
				(enabled no)
				(sheetname "")
			)
			(fill
				(thermal_gap 0.5)
				(thermal_bridge_width 0.5)
				(island_removal_mode 0)
			)
			(polygon
				(pts
					(xy 455.407522 -275.648674) (xy 448.333622 -275.648674) (xy 448.333622 -282.582874) (xy 449.438522 -282.582874)
					(xy 449.438522 -278.468074) (xy 454.061322 -278.468074) (xy 454.061322 -282.582874) (xy 455.407522 -282.582874)
				)
			)
		)
		(zone
			(layer "F.Cu")
			(hatch none 0.5)
			(connect_pads
				(clearance 0)
			)
			(min_thickness 0.25)
			(keepout
				(tracks not_allowed)
				(vias allowed)
				(pads allowed)
				(copperpour not_allowed)
				(footprints allowed)
			)
			(placement
				(enabled no)
				(sheetname "")
			)
			(fill
				(thermal_gap 0.5)
				(thermal_bridge_width 0.5)
				(island_removal_mode 0)
			)
			(polygon
				(pts
					(xy 455.407522 -242.171474) (xy 448.333622 -242.171474) (xy 448.333622 -235.237274) (xy 449.438522 -235.237274)
					(xy 449.438522 -239.352074) (xy 454.061322 -239.352074) (xy 454.061322 -235.237274) (xy 455.407522 -235.237274)
				)
			)
		)
		(zone
			(layer "F.Cu")
			(hatch none 0.5)
			(connect_pads
				(clearance 0)
			)
			(min_thickness 0.25)
			(keepout
				(tracks allowed)
				(vias not_allowed)
				(pads allowed)
				(copperpour not_allowed)
				(footprints allowed)
			)
			(placement
				(enabled no)
				(sheetname "")
			)
			(fill
				(thermal_gap 0.5)
				(thermal_bridge_width 0.5)
				(island_removal_mode 0)
			)
			(polygon
				(pts
					(xy 455.407522 -242.171474) (xy 448.333622 -242.171474) (xy 448.333622 -235.237274) (xy 449.438522 -235.237274)
					(xy 449.438522 -239.352074) (xy 454.061322 -239.352074) (xy 454.061322 -235.237274) (xy 455.407522 -235.237274)
				)
			)
		)
		(zone
			(layers "F.Cu" "B.Cu" "In1.Cu" "In2.Cu" "In3.Cu" "In4.Cu" "In5.Cu" "In6.Cu")
			(hatch none 0.5)
			(connect_pads
				(clearance 0)
			)
			(min_thickness 0.25)
			(keepout
				(tracks not_allowed)
				(vias allowed)
				(pads allowed)
				(copperpour not_allowed)
				(footprints allowed)
			)
			(placement
				(enabled no)
				(sheetname "")
			)
			(fill
				(thermal_gap 0.5)
				(thermal_bridge_width 0.5)
				(island_removal_mode 0)
			)
			(polygon
				(pts
					(arc
						(start 452.524622 -240.03508)
						(mid 450.975222 -240.03508)
						(end 452.524622 -240.03508)
					)
				)
			)
		)
		(zone
			(layers "F.Cu" "B.Cu" "In1.Cu" "In2.Cu" "In3.Cu" "In4.Cu" "In5.Cu" "In6.Cu")
			(hatch none 0.5)
			(connect_pads
				(clearance 0)
			)
			(min_thickness 0.25)
			(keepout
				(tracks not_allowed)
				(vias allowed)
				(pads allowed)
				(copperpour not_allowed)
				(footprints allowed)
			)
			(placement
				(enabled no)
				(sheetname "")
			)
			(fill
				(thermal_gap 0.5)
				(thermal_bridge_width 0.5)
				(island_removal_mode 0)
			)
			(polygon
				(pts
					(arc
						(start 452.727822 -277.785068)
						(mid 450.772022 -277.785068)
						(end 452.727822 -277.785068)
					)
				)
			)
		)
	)
	(footprint ""
		(layer "F.Cu")
		(at 250.327668 -222.9612)
		(property "Reference" "R107"
			(at 0 0 0)
			(layer "F.SilkS")
			(hide yes)
			(effects
				(font
					(size 1.27 1.27)
				)
			)
		)
		(property "Value" "4K7R2F-GP"
			(at 0.064008 -3.993896 0)
			(unlocked yes)
			(layer "F.Fab")
			(hide yes)
			(effects
				(font
					(size 1.016 1.016)
					(thickness 0.1524)
				)
			)
		)
		(property "Device Type" "R402H16"
			(at 0.064008 -5.517896 0)
			(unlocked yes)
			(layer "F.Fab")
			(hide yes)
			(effects
				(font
					(size 1.016 1.016)
					(thickness 0.1524)
				)
			)
		)
		(duplicate_pad_numbers_are_jumpers no)
		(fp_line
			(start -0.508 -0.9398)
			(end -0.508 0.9398)
			(stroke
				(width 0.1524)
				(type default)
			)
			(layer "F.SilkS")
		)
		(fp_line
			(start 0.508 -0.9398)
			(end -0.508 -0.9398)
			(stroke
				(width 0.1524)
				(type default)
			)
			(layer "F.SilkS")
		)
		(fp_rect
			(start -0.508 0.9398)
			(end 0.508 -0.9398)
			(stroke
				(width 0)
				(type default)
			)
			(fill no)
			(layer "F.CrtYd")
		)
		(fp_rect
			(start -0.508 0.9398)
			(end 0.508 -0.9398)
			(stroke
				(width 0)
				(type default)
			)
			(fill no)
			(layer "F.Fab")
		)
		(pad "1" smd custom
			(at 0 -0.4445)
			(size 0.1397 0.1397)
			(layers "F.Cu" "F.Mask" "F.Paste")
			(net "P3V3_STBY_B")
			(options
				(clearance outline)
				(anchor circle)
			)
			(primitives
				(gr_poly
					(pts
						(arc
							(start -0.1778 -0.2794)
							(mid -0.249642 -0.249642)
							(end -0.2794 -0.1778)
						)
						(arc
							(start -0.2794 0.1778)
							(mid -0.249642 0.249642)
							(end -0.1778 0.2794)
						)
						(arc
							(start 0.1778 0.2794)
							(mid 0.249642 0.249642)
							(end 0.2794 0.1778)
						)
						(arc
							(start 0.2794 -0.1778)
							(mid 0.249642 -0.249642)
							(end 0.1778 -0.2794)
						)
					)
					(width 0)
					(fill yes)
				)
			)
		)
		(pad "2" smd custom
			(at 0 0.4445)
			(size 0.1397 0.1397)
			(layers "F.Cu" "F.Mask" "F.Paste")
			(net "EEPROM_A1")
			(options
				(clearance outline)
				(anchor circle)
			)
			(primitives
				(gr_poly
					(pts
						(arc
							(start -0.1778 -0.2794)
							(mid -0.249642 -0.249642)
							(end -0.2794 -0.1778)
						)
						(arc
							(start -0.2794 0.1778)
							(mid -0.249642 0.249642)
							(end -0.1778 0.2794)
						)
						(arc
							(start 0.1778 0.2794)
							(mid 0.249642 0.249642)
							(end 0.2794 0.1778)
						)
						(arc
							(start 0.2794 -0.1778)
							(mid 0.249642 -0.249642)
							(end 0.1778 -0.2794)
						)
					)
					(width 0)
					(fill yes)
				)
			)
		)
	)
	(footprint ""
		(layer "F.Cu")
		(at 112.450118 -180.399944)
		(property "Reference" "LED4"
			(at 0 0 0)
			(layer "F.SilkS")
			(hide yes)
			(effects
				(font
					(size 1.27 1.27)
				)
			)
		)
		(property "Value" "LED-BY-19-GP"
			(at -2.132076 1.414018 0)
			(unlocked yes)
			(layer "F.Fab")
			(hide yes)
			(effects
				(font
					(size 1.016 1.016)
					(thickness 0.1524)
				)
			)
		)
		(property "Device Type" "LED-1615-4PH26"
			(at -2.132076 -0.109982 0)
			(unlocked yes)
			(layer "F.Fab")
			(hide yes)
			(effects
				(font
					(size 1.016 1.016)
					(thickness 0.1524)
				)
			)
		)
		(duplicate_pad_numbers_are_jumpers no)
		(fp_line
			(start -1.2954 0.254)
			(end -1.2954 1.6002)
			(stroke
				(width 0.508)
				(type default)
			)
			(layer "F.SilkS")
		)
		(fp_line
			(start -1.2954 1.6002)
			(end 1.2954 1.6002)
			(stroke
				(width 0.508)
				(type default)
			)
			(layer "F.SilkS")
		)
		(fp_line
			(start -1.1176 -1.4224)
			(end 1.1176 -1.4224)
			(stroke
				(width 0.1524)
				(type default)
			)
			(layer "F.SilkS")
		)
		(fp_line
			(start -1.1176 1.4224)
			(end -1.1176 -1.4224)
			(stroke
				(width 0.1524)
				(type default)
			)
			(layer "F.SilkS")
		)
		(fp_line
			(start 1.1176 -1.4224)
			(end 1.1176 1.4224)
			(stroke
				(width 0.1524)
				(type default)
			)
			(layer "F.SilkS")
		)
		(fp_line
			(start 1.1176 1.4224)
			(end -1.1176 1.4224)
			(stroke
				(width 0.1524)
				(type default)
			)
			(layer "F.SilkS")
		)
		(fp_line
			(start 1.2954 1.6002)
			(end 1.2954 0.254)
			(stroke
				(width 0.508)
				(type default)
			)
			(layer "F.SilkS")
		)
		(fp_rect
			(start -0.7493 0.8001)
			(end 0.7493 -0.8001)
			(stroke
				(width 0)
				(type default)
			)
			(fill no)
			(layer "F.CrtYd")
		)
		(fp_poly
			(pts
				(xy -1.3716 1.6764) (xy -1.3716 -1.6764) (xy 1.3716 -1.6764) (xy 1.3716 0.0635) (xy 0.7493 0.0635)
				(xy 0.7493 -0.8001) (xy -0.7493 -0.8001) (xy -0.7493 0.8001) (xy 0.7493 0.8001) (xy 0.7493 0.0762)
				(xy 1.3716 0.0762) (xy 1.3716 1.6764)
			)
			(stroke
				(width 0)
				(type default)
			)
			(fill no)
			(layer "F.CrtYd")
		)
		(fp_rect
			(start -1.3716 1.6764)
			(end 1.3716 -1.6764)
			(stroke
				(width 0)
				(type default)
			)
			(fill no)
			(layer "F.Fab")
		)
		(pad "1" smd rect
			(at 0.50038 -0.73025)
			(size 0.7112 0.8636)
			(layers "F.Cu" "F.Mask" "F.Paste")
			(net "DRV_ACT_3")
		)
		(pad "2" smd rect
			(at -0.50038 -0.73025)
			(size 0.7112 0.8636)
			(layers "F.Cu" "F.Mask" "F.Paste")
			(net "FLT_HDD3")
		)
		(pad "3" smd rect
			(at 0.50038 0.73025)
			(size 0.7112 0.8636)
			(layers "F.Cu" "F.Mask" "F.Paste")
			(net "DRV_ACT_3_N")
		)
		(pad "4" smd rect
			(at -0.50038 0.73025)
			(size 0.7112 0.8636)
			(layers "F.Cu" "F.Mask" "F.Paste")
			(net "FLT_HDD3_N")
		)
	)
)
